# TIMECARD (Time Appliance Project (Time Card)) — schematic netlist excerpt (pin names and nets, part order shuffled) for the footprints in the layout excerpt that follows; sources: Cadence DE-HDL packaged netlist, KiCad conversion of R4006-B0001-02_R01.brd

R176  RESISTOR  33OHM 1%  pkg SMC_0402R_H016  page 16 : \1\ = PCIE_SMCLK ; \2\ = EEPROM_SCL
R169  RESISTOR  330OHM 1%  pkg SMC_0402R_H016  page 26 : \1\ = UNNAMED_14_OPTICAL_I289_A ; \2\ = XP3R3V_FT4232

(kicad_pcb
	(version 20260206)
	(generator "pcbnew")
	(generator_version "10.0")
	(general
		(thickness 1.6)
		(legacy_teardrops no)
	)
	(paper "A4")
	(title_block
		(title "timecard-production-celestica-r4006 — R4006-B0001-02_R01.brd")
		(comment 1 "Time Appliance Project (Time Card) / footprints 706-707 of 1113")
	)
	(layers
		(0 "F.Cu" signal "TOP")
		(4 "In1.Cu" signal "L02_GND1")
		(6 "In2.Cu" signal "L03_SIG1")
		(8 "In3.Cu" signal "L04_GND2")
		(10 "In4.Cu" signal "L05_VCC1")
		(12 "In5.Cu" signal "L06_VCC2")
		(14 "In6.Cu" signal "L07_GND3")
		(16 "In7.Cu" signal "L08_SIG2")
		(18 "In8.Cu" signal "L09_GND4")
		(2 "B.Cu" signal "BOTTOM")
		(9 "F.Adhes" user "F.Adhesive")
		(11 "B.Adhes" user "B.Adhesive")
		(13 "F.Paste" user "Package Geometry/Pastemask Top")
		(15 "B.Paste" user "Package Geometry/Pastemask Bottom")
		(5 "F.SilkS" user "Ref Des/Silkscreen Top")
		(7 "B.SilkS" user "Ref Des/Silkscreen Bottom")
		(1 "F.Mask" user "Board Geometry/Soldermask Top")
		(3 "B.Mask" user "Board Geometry/Soldermask Bottom")
		(17 "Dwgs.User" user "User.Drawings")
		(19 "Cmts.User" user "User.Comments")
		(21 "Eco1.User" user "User.Eco1")
		(23 "Eco2.User" user "User.Eco2")
		(25 "Edge.Cuts" user "Board Geometry/Outline")
		(27 "Margin" user)
		(31 "F.CrtYd" user "Package Geometry/Place Bound Top")
		(29 "B.CrtYd" user "Package Geometry/Place Bound Bottom")
		(35 "F.Fab" user "Ref Des/Assembly Top")
		(33 "B.Fab" user "Ref Des/Assembly Bottom")
	)
	(footprint ""
		(layer "B.Cu")
		(at 156.083 -104.521 90)
		(property "Reference" "R169"
			(at -1.27 1.23063 270)
			(unlocked yes)
			(layer "B.SilkS")
			(effects
				(font
					(size 0.7874 0.5842)
					(thickness 0.1524)
				)
				(justify mirror)
			)
		)
		(property "Value" "VAL*"
			(at -0.02032 2.13233 90)
			(unlocked yes)
			(layer "B.Fab")
			(hide yes)
			(effects
				(font
					(size 0.7874 0.5842)
					(thickness 0.1524)
				)
				(justify mirror)
			)
		)
		(property "Tolerance" "TOL*"
			(at -0.044704 3.05435 90)
			(unlocked yes)
			(layer "Cmts.User")
			(hide yes)
			(effects
				(font
					(size 0.7874 0.5842)
					(thickness 0.1524)
				)
				(justify mirror)
			)
		)
		(property "User Part Number" "PARTNUM*"
			(at -0.02032 4.024884 90)
			(unlocked yes)
			(layer "Cmts.User")
			(hide yes)
			(effects
				(font
					(size 0.7874 0.5842)
					(thickness 0.1524)
				)
				(justify mirror)
			)
		)
		(property "Device Type" "RESISTOR-G155-13300-01,330OHM,A"
			(at -0.008382 1.210564 90)
			(unlocked yes)
			(layer "B.Fab")
			(hide yes)
			(effects
				(font
					(size 0.7874 0.5842)
					(thickness 0.1524)
				)
				(justify mirror)
			)
		)
		(duplicate_pad_numbers_are_jumpers no)
		(fp_line
			(start 1.143 -0.5588)
			(end 1.143 0.5588)
			(stroke
				(width 0.1)
				(type default)
			)
			(layer "B.SilkS")
		)
		(fp_line
			(start -1.143 -0.5588)
			(end 1.143 -0.5588)
			(stroke
				(width 0.1)
				(type default)
			)
			(layer "B.SilkS")
		)
		(fp_line
			(start 1.143 0.5588)
			(end -1.143 0.5588)
			(stroke
				(width 0.1)
				(type default)
			)
			(layer "B.SilkS")
		)
		(fp_line
			(start -1.143 0.5588)
			(end -1.143 -0.5588)
			(stroke
				(width 0.1)
				(type default)
			)
			(layer "B.SilkS")
		)
		(fp_rect
			(start -1.143 0.5588)
			(end 1.143 -0.5588)
			(stroke
				(width 0)
				(type default)
			)
			(fill no)
			(layer "B.CrtYd")
		)
		(fp_line
			(start 0.508 -0.3048)
			(end 0.508 0.3048)
			(stroke
				(width 0.1)
				(type default)
			)
			(layer "B.Fab")
		)
		(fp_line
			(start -0.508 -0.3048)
			(end 0.508 -0.3048)
			(stroke
				(width 0.1)
				(type default)
			)
			(layer "B.Fab")
		)
		(fp_line
			(start 0.508 0.3048)
			(end -0.508 0.3048)
			(stroke
				(width 0.1)
				(type default)
			)
			(layer "B.Fab")
		)
		(fp_line
			(start -0.508 0.3048)
			(end -0.508 -0.3048)
			(stroke
				(width 0.1)
				(type default)
			)
			(layer "B.Fab")
		)
		(pad "1" smd rect
			(at 0.5334 0 270)
			(size 0.7112 0.6096)
			(layers "B.Cu" "B.Mask" "B.Paste")
			(net "UNNAMED_14_OPTICAL_I289_A")
		)
		(pad "2" smd rect
			(at -0.5334 0 270)
			(size 0.7112 0.6096)
			(layers "B.Cu" "B.Mask" "B.Paste")
			(net "XP3R3V_FT4232")
		)
		(zone
			(layer "B.Cu")
			(hatch none 0.5)
			(connect_pads
				(clearance 0)
			)
			(min_thickness 0.25)
			(keepout
				(tracks allowed)
				(vias not_allowed)
				(pads allowed)
				(copperpour not_allowed)
				(footprints allowed)
			)
			(placement
				(enabled no)
				(sheetname "")
			)
			(fill
				(thermal_gap 0.5)
				(thermal_bridge_width 0.5)
				(island_removal_mode 0)
			)
			(polygon
				(pts
					(xy 156.3878 -104.4448) (xy 156.3878 -104.5972) (xy 155.7782 -104.5972) (xy 155.7782 -104.4448)
				)
			)
		)
	)
	(footprint ""
		(layer "B.Cu")
		(at 33.77438 -17.9832)
		(property "Reference" "R176"
			(at 3.18262 1.25857 0)
			(unlocked yes)
			(layer "B.SilkS")
			(effects
				(font
					(size 0.7874 0.5842)
					(thickness 0.1524)
				)
				(justify mirror)
			)
		)
		(property "Value" "VAL*"
			(at -0.02032 2.13233 0)
			(unlocked yes)
			(layer "B.Fab")
			(hide yes)
			(effects
				(font
					(size 0.7874 0.5842)
					(thickness 0.1524)
				)
				(justify mirror)
			)
		)
		(property "Tolerance" "TOL*"
			(at -0.044704 3.05435 0)
			(unlocked yes)
			(layer "Cmts.User")
			(hide yes)
			(effects
				(font
					(size 0.7874 0.5842)
					(thickness 0.1524)
				)
				(justify mirror)
			)
		)
		(property "User Part Number" "PARTNUM*"
			(at -0.02032 4.024884 0)
			(unlocked yes)
			(layer "Cmts.User")
			(hide yes)
			(effects
				(font
					(size 0.7874 0.5842)
					(thickness 0.1524)
				)
				(justify mirror)
			)
		)
		(property "Device Type" "RESISTOR-G155-133R0-01,33OHM,1%"
			(at -0.008382 1.210564 0)
			(unlocked yes)
			(layer "B.Fab")
			(hide yes)
			(effects
				(font
					(size 0.7874 0.5842)
					(thickness 0.1524)
				)
				(justify mirror)
			)
		)
		(duplicate_pad_numbers_are_jumpers no)
		(fp_line
			(start -1.143 -0.5588)
			(end 1.143 -0.5588)
			(stroke
				(width 0.1)
				(type default)
			)
			(layer "B.SilkS")
		)
		(fp_line
			(start -1.143 0.5588)
			(end -1.143 -0.5588)
			(stroke
				(width 0.1)
				(type default)
			)
			(layer "B.SilkS")
		)
		(fp_line
			(start 1.143 -0.5588)
			(end 1.143 0.5588)
			(stroke
				(width 0.1)
				(type default)
			)
			(layer "B.SilkS")
		)
		(fp_line
			(start 1.143 0.5588)
			(end -1.143 0.5588)
			(stroke
				(width 0.1)
				(type default)
			)
			(layer "B.SilkS")
		)
		(fp_rect
			(start -1.143 0.5588)
			(end 1.143 -0.5588)
			(stroke
				(width 0)
				(type default)
			)
			(fill no)
			(layer "B.CrtYd")
		)
		(fp_line
			(start -0.508 -0.3048)
			(end 0.508 -0.3048)
			(stroke
				(width 0.1)
				(type default)
			)
			(layer "B.Fab")
		)
		(fp_line
			(start -0.508 0.3048)
			(end -0.508 -0.3048)
			(stroke
				(width 0.1)
				(type default)
			)
			(layer "B.Fab")
		)
		(fp_line
			(start 0.508 -0.3048)
			(end 0.508 0.3048)
			(stroke
				(width 0.1)
				(type default)
			)
			(layer "B.Fab")
		)
		(fp_line
			(start 0.508 0.3048)
			(end -0.508 0.3048)
			(stroke
				(width 0.1)
				(type default)
			)
			(layer "B.Fab")
		)
		(pad "1" smd rect
			(at 0.5334 0 180)
			(size 0.7112 0.6096)
			(layers "B.Cu" "B.Mask" "B.Paste")
			(net "PCIE_SMCLK")
		)
		(pad "2" smd rect
			(at -0.5334 0 180)
			(size 0.7112 0.6096)
			(layers "B.Cu" "B.Mask" "B.Paste")
			(net "EEPROM_SCL")
		)
		(zone
			(layer "B.Cu")
			(hatch none 0.5)
			(connect_pads
				(clearance 0)
			)
			(min_thickness 0.25)
			(keepout
				(tracks allowed)
				(vias not_allowed)
				(pads allowed)
				(copperpour not_allowed)
				(footprints allowed)
			)
			(placement
				(enabled no)
				(sheetname "")
			)
			(fill
				(thermal_gap 0.5)
				(thermal_bridge_width 0.5)
				(island_removal_mode 0)
			)
			(polygon
				(pts
					(xy 33.69818 -17.6784) (xy 33.85058 -17.6784) (xy 33.85058 -18.288) (xy 33.69818 -18.288)
				)
			)
		)
	)
)
